(kicad_pcb
	(version 20260206)
	(generator "pcbnew")
	(generator_version "10.0")
	(general
		(thickness 1.6)
		(legacy_teardrops no)
	)
	(paper "A4")
	(title_block
		(title "04192023_DAF0TMB3IC0_F0TG_MB_C_brd_V02_OCP.brd")
		(comment 1 "Grand Teton / footprints 6461-6466 of 8354")
	)
	(layers
		(0 "F.Cu" signal "TOP")
		(4 "In1.Cu" signal "GND")
		(6 "In2.Cu" signal "IN1")
		(8 "In3.Cu" signal "GND1")
		(10 "In4.Cu" signal "IN2")
		(12 "In5.Cu" signal "GND2")
		(14 "In6.Cu" signal "IN3")
		(16 "In7.Cu" signal "GND3")
		(18 "In8.Cu" signal "VCC")
		(20 "In9.Cu" signal "VCC1")
		(22 "In10.Cu" signal "GND4")
		(24 "In11.Cu" signal "IN4")
		(26 "In12.Cu" signal "GND5")
		(28 "In13.Cu" signal "IN5")
		(30 "In14.Cu" signal "GND6")
		(32 "In15.Cu" signal "IN6")
		(34 "In16.Cu" signal "GND7")
		(2 "B.Cu" signal "BOTTOM")
		(9 "F.Adhes" user "F.Adhesive")
		(11 "B.Adhes" user "B.Adhesive")
		(13 "F.Paste" user "Package Geometry/Pastemask Top")
		(15 "B.Paste" user "Package Geometry/Pastemask Bottom")
		(5 "F.SilkS" user "Ref Des/Silkscreen Top")
		(7 "B.SilkS" user "Ref Des/Silkscreen Bottom")
		(1 "F.Mask" user "Board Geometry/Soldermask Top")
		(3 "B.Mask" user "Board Geometry/Soldermask Bottom")
		(17 "Dwgs.User" user "User.Drawings")
		(19 "Cmts.User" user "User.Comments")
		(21 "Eco1.User" user "User.Eco1")
		(23 "Eco2.User" user "User.Eco2")
		(25 "Edge.Cuts" user "Board Geometry/Outline")
		(27 "Margin" user)
		(31 "F.CrtYd" user "Package Geometry/Place Bound Top")
		(29 "B.CrtYd" user "Package Geometry/Place Bound Bottom")
		(35 "F.Fab" user "Ref Des/Assembly Top")
		(33 "B.Fab" user "Ref Des/Assembly Bottom")
	)
	(footprint ""
		(layer "B.Cu")
		(at 354.406454 -267.52931)
		(property "Reference" "C2253"
			(at 0 0 0)
			(layer "B.SilkS")
			(hide yes)
			(effects
				(font
					(size 1.27 1.27)
				)
				(justify mirror)
			)
		)
		(property "Value" ""
			(at 0 0 0)
			(layer "B.Fab")
			(effects
				(font
					(size 1.27 1.27)
				)
				(justify mirror)
			)
		)
		(duplicate_pad_numbers_are_jumpers no)
		(fp_line
			(start -0.7874 -0.4064)
			(end -0.7874 0.4064)
			(stroke
				(width 0.1524)
				(type default)
			)
			(layer "B.SilkS")
		)
		(fp_line
			(start -0.7874 0.4064)
			(end 0.7874 0.4064)
			(stroke
				(width 0.1524)
				(type default)
			)
			(layer "B.SilkS")
		)
		(fp_line
			(start 0.7874 -0.4064)
			(end -0.7874 -0.4064)
			(stroke
				(width 0.1524)
				(type default)
			)
			(layer "B.SilkS")
		)
		(fp_line
			(start 0.7874 0.4064)
			(end 0.7874 -0.4064)
			(stroke
				(width 0.1524)
				(type default)
			)
			(layer "B.SilkS")
		)
		(fp_line
			(start -0.67945 -0.3048)
			(end -0.67945 0.3048)
			(stroke
				(width 0.1)
				(type default)
			)
			(layer "B.Fab")
		)
		(fp_line
			(start -0.67945 0.3048)
			(end -0.120396 0.3048)
			(stroke
				(width 0.1)
				(type default)
			)
			(layer "B.Fab")
		)
		(fp_line
			(start -0.12065 -0.3048)
			(end -0.67945 -0.3048)
			(stroke
				(width 0.1)
				(type default)
			)
			(layer "B.Fab")
		)
		(fp_line
			(start -0.12065 -0.2794)
			(end -0.12065 -0.3048)
			(stroke
				(width 0.1)
				(type default)
			)
			(layer "B.Fab")
		)
		(fp_line
			(start -0.120396 0.2794)
			(end 0.12065 0.2794)
			(stroke
				(width 0.1)
				(type default)
			)
			(layer "B.Fab")
		)
		(fp_line
			(start -0.120396 0.3048)
			(end -0.120396 0.2794)
			(stroke
				(width 0.1)
				(type default)
			)
			(layer "B.Fab")
		)
		(fp_line
			(start 0.12065 -0.305054)
			(end 0.12065 -0.2794)
			(stroke
				(width 0.1)
				(type default)
			)
			(layer "B.Fab")
		)
		(fp_line
			(start 0.12065 -0.2794)
			(end -0.12065 -0.2794)
			(stroke
				(width 0.1)
				(type default)
			)
			(layer "B.Fab")
		)
		(fp_line
			(start 0.12065 0.2794)
			(end 0.12065 0.3048)
			(stroke
				(width 0.1)
				(type default)
			)
			(layer "B.Fab")
		)
		(fp_line
			(start 0.12065 0.3048)
			(end 0.67945 0.3048)
			(stroke
				(width 0.1)
				(type default)
			)
			(layer "B.Fab")
		)
		(fp_line
			(start 0.67945 -0.305054)
			(end 0.12065 -0.305054)
			(stroke
				(width 0.1)
				(type default)
			)
			(layer "B.Fab")
		)
		(fp_line
			(start 0.67945 0.3048)
			(end 0.67945 -0.305054)
			(stroke
				(width 0.1)
				(type default)
			)
			(layer "B.Fab")
		)
		(pad "1" smd circle
			(at 0.40005 0 180)
			(size 0 0)
			(layers "B.Cu" "B.Mask" "B.Paste")
			(net "PVDDCR_CPU1_P0")
		)
		(pad "2" smd circle
			(at -0.40005 0 180)
			(size 0 0)
			(layers "B.Cu" "B.Mask" "B.Paste")
			(net "GND")
		)
	)
	(footprint ""
		(layer "B.Cu")
		(at 309.81777 -346.784168 90)
		(property "Reference" "PC125_4"
			(at 0 0 90)
			(layer "B.SilkS")
			(hide yes)
			(effects
				(font
					(size 1.27 1.27)
				)
				(justify mirror)
			)
		)
		(property "Value" ""
			(at 0 0 90)
			(layer "B.Fab")
			(effects
				(font
					(size 1.27 1.27)
				)
				(justify mirror)
			)
		)
		(duplicate_pad_numbers_are_jumpers no)
		(fp_line
			(start 1.524 -0.762)
			(end -1.524 -0.762)
			(stroke
				(width 0.1524)
				(type default)
			)
			(layer "B.SilkS")
		)
		(fp_line
			(start -1.524 -0.762)
			(end -1.524 0.762)
			(stroke
				(width 0.1524)
				(type default)
			)
			(layer "B.SilkS")
		)
		(fp_line
			(start 1.524 0.762)
			(end 1.524 -0.762)
			(stroke
				(width 0.1524)
				(type default)
			)
			(layer "B.SilkS")
		)
		(fp_line
			(start -1.524 0.762)
			(end 1.524 0.762)
			(stroke
				(width 0.1524)
				(type default)
			)
			(layer "B.SilkS")
		)
		(fp_line
			(start 1.1049 -0.724916)
			(end 1.1049 0.724916)
			(stroke
				(width 0.1)
				(type default)
			)
			(layer "B.Fab")
		)
		(fp_line
			(start -1.1049 -0.724916)
			(end 1.1049 -0.724916)
			(stroke
				(width 0.1)
				(type default)
			)
			(layer "B.Fab")
		)
		(fp_line
			(start 1.1049 0.724916)
			(end -1.1049 0.724916)
			(stroke
				(width 0.1)
				(type default)
			)
			(layer "B.Fab")
		)
		(fp_line
			(start -1.1049 0.724916)
			(end -1.1049 -0.724916)
			(stroke
				(width 0.1)
				(type default)
			)
			(layer "B.Fab")
		)
		(pad "1" smd rect
			(at 0.889 0 90)
			(size 1.016 1.27)
			(layers "B.Cu" "B.Mask" "B.Paste")
			(net "SW_P12V_AUX_PVDDCR_CPU1_P0_FLT")
		)
		(pad "2" smd rect
			(at -0.889 0 90)
			(size 1.016 1.27)
			(layers "B.Cu" "B.Mask" "B.Paste")
			(net "GND")
		)
	)
	(footprint ""
		(layer "B.Cu")
		(at 141.623542 -384.66268 180)
		(property "Reference" "R880"
			(at 0 0 0)
			(layer "B.SilkS")
			(hide yes)
			(effects
				(font
					(size 1.27 1.27)
				)
				(justify mirror)
			)
		)
		(property "Value" ""
			(at 0 0 0)
			(layer "B.Fab")
			(effects
				(font
					(size 1.27 1.27)
				)
				(justify mirror)
			)
		)
		(duplicate_pad_numbers_are_jumpers no)
		(fp_line
			(start 0.32512 0.175006)
			(end 0.32512 -0.175006)
			(stroke
				(width 0.1)
				(type default)
			)
			(layer "B.Fab")
		)
		(fp_line
			(start 0.32512 -0.175006)
			(end -0.32512 -0.175006)
			(stroke
				(width 0.1)
				(type default)
			)
			(layer "B.Fab")
		)
		(fp_line
			(start -0.32512 0.175006)
			(end 0.32512 0.175006)
			(stroke
				(width 0.1)
				(type default)
			)
			(layer "B.Fab")
		)
		(fp_line
			(start -0.32512 -0.175006)
			(end -0.32512 0.175006)
			(stroke
				(width 0.1)
				(type default)
			)
			(layer "B.Fab")
		)
		(pad "1" smd rect
			(at 0.2667 0)
			(size 0.3048 0.381)
			(layers "B.Cu" "B.Mask" "B.Paste")
			(net "P1V8_CPU1_RT_1D")
		)
		(pad "2" smd rect
			(at -0.2667 0 180)
			(size 0.3048 0.381)
			(layers "B.Cu" "B.Mask" "B.Paste")
			(net "TEST1_RT_CPU1_P2")
		)
	)
	(footprint ""
		(layer "B.Cu")
		(at 398.680178 -324.812152 180)
		(property "Reference" "R1592"
			(at 0 0 0)
			(layer "B.SilkS")
			(hide yes)
			(effects
				(font
					(size 1.27 1.27)
				)
				(justify mirror)
			)
		)
		(property "Value" ""
			(at 0 0 0)
			(layer "B.Fab")
			(effects
				(font
					(size 1.27 1.27)
				)
				(justify mirror)
			)
		)
		(duplicate_pad_numbers_are_jumpers no)
		(fp_line
			(start 0.7874 0.4064)
			(end 0.7874 -0.4064)
			(stroke
				(width 0.1524)
				(type default)
			)
			(layer "B.SilkS")
		)
		(fp_line
			(start 0.7874 -0.4064)
			(end -0.7874 -0.4064)
			(stroke
				(width 0.1524)
				(type default)
			)
			(layer "B.SilkS")
		)
		(fp_line
			(start -0.7874 0.4064)
			(end 0.7874 0.4064)
			(stroke
				(width 0.1524)
				(type default)
			)
			(layer "B.SilkS")
		)
		(fp_line
			(start -0.7874 -0.4064)
			(end -0.7874 0.4064)
			(stroke
				(width 0.1524)
				(type default)
			)
			(layer "B.SilkS")
		)
		(fp_line
			(start 0.67945 0.3048)
			(end 0.67945 -0.305054)
			(stroke
				(width 0.1)
				(type default)
			)
			(layer "B.Fab")
		)
		(fp_line
			(start 0.67945 -0.305054)
			(end 0.12065 -0.305054)
			(stroke
				(width 0.1)
				(type default)
			)
			(layer "B.Fab")
		)
		(fp_line
			(start 0.12065 0.3048)
			(end 0.67945 0.3048)
			(stroke
				(width 0.1)
				(type default)
			)
			(layer "B.Fab")
		)
		(fp_line
			(start 0.12065 0.2794)
			(end 0.12065 0.3048)
			(stroke
				(width 0.1)
				(type default)
			)
			(layer "B.Fab")
		)
		(fp_line
			(start 0.12065 -0.2794)
			(end -0.12065 -0.2794)
			(stroke
				(width 0.1)
				(type default)
			)
			(layer "B.Fab")
		)
		(fp_line
			(start 0.12065 -0.305054)
			(end 0.12065 -0.2794)
			(stroke
				(width 0.1)
				(type default)
			)
			(layer "B.Fab")
		)
		(fp_line
			(start -0.120396 0.3048)
			(end -0.120396 0.2794)
			(stroke
				(width 0.1)
				(type default)
			)
			(layer "B.Fab")
		)
		(fp_line
			(start -0.120396 0.2794)
			(end 0.12065 0.2794)
			(stroke
				(width 0.1)
				(type default)
			)
			(layer "B.Fab")
		)
		(fp_line
			(start -0.12065 -0.2794)
			(end -0.12065 -0.3048)
			(stroke
				(width 0.1)
				(type default)
			)
			(layer "B.Fab")
		)
		(fp_line
			(start -0.12065 -0.3048)
			(end -0.67945 -0.3048)
			(stroke
				(width 0.1)
				(type default)
			)
			(layer "B.Fab")
		)
		(fp_line
			(start -0.67945 0.3048)
			(end -0.120396 0.3048)
			(stroke
				(width 0.1)
				(type default)
			)
			(layer "B.Fab")
		)
		(fp_line
			(start -0.67945 -0.3048)
			(end -0.67945 0.3048)
			(stroke
				(width 0.1)
				(type default)
			)
			(layer "B.Fab")
		)
		(pad "1" smd rect
			(at 0.40005 0 180)
			(size 0.4572 0.508)
			(layers "B.Cu" "B.Mask" "B.Paste")
			(net "ESPI_CPU0_CS1_N")
		)
		(pad "2" smd rect
			(at -0.40005 0 180)
			(size 0.4572 0.508)
			(layers "B.Cu" "B.Mask" "B.Paste")
			(net "CPU0_ESPI_CS0_N")
		)
	)
	(footprint ""
		(layer "B.Cu")
		(at 93.4212 -138.176)
		(property "Reference" "R308"
			(at 0 0 0)
			(layer "B.SilkS")
			(hide yes)
			(effects
				(font
					(size 1.27 1.27)
				)
				(justify mirror)
			)
		)
		(property "Value" ""
			(at 0 0 0)
			(layer "B.Fab")
			(effects
				(font
					(size 1.27 1.27)
				)
				(justify mirror)
			)
		)
		(duplicate_pad_numbers_are_jumpers no)
		(fp_line
			(start -0.7874 -0.4064)
			(end -0.7874 0.4064)
			(stroke
				(width 0.1524)
				(type default)
			)
			(layer "B.SilkS")
		)
		(fp_line
			(start -0.7874 0.4064)
			(end 0.7874 0.4064)
			(stroke
				(width 0.1524)
				(type default)
			)
			(layer "B.SilkS")
		)
		(fp_line
			(start 0.7874 -0.4064)
			(end -0.7874 -0.4064)
			(stroke
				(width 0.1524)
				(type default)
			)
			(layer "B.SilkS")
		)
		(fp_line
			(start 0.7874 0.4064)
			(end 0.7874 -0.4064)
			(stroke
				(width 0.1524)
				(type default)
			)
			(layer "B.SilkS")
		)
		(fp_line
			(start -0.67945 -0.3048)
			(end -0.67945 0.3048)
			(stroke
				(width 0.1)
				(type default)
			)
			(layer "B.Fab")
		)
		(fp_line
			(start -0.67945 0.3048)
			(end -0.120396 0.3048)
			(stroke
				(width 0.1)
				(type default)
			)
			(layer "B.Fab")
		)
		(fp_line
			(start -0.12065 -0.3048)
			(end -0.67945 -0.3048)
			(stroke
				(width 0.1)
				(type default)
			)
			(layer "B.Fab")
		)
		(fp_line
			(start -0.12065 -0.2794)
			(end -0.12065 -0.3048)
			(stroke
				(width 0.1)
				(type default)
			)
			(layer "B.Fab")
		)
		(fp_line
			(start -0.120396 0.2794)
			(end 0.12065 0.2794)
			(stroke
				(width 0.1)
				(type default)
			)
			(layer "B.Fab")
		)
		(fp_line
			(start -0.120396 0.3048)
			(end -0.120396 0.2794)
			(stroke
				(width 0.1)
				(type default)
			)
			(layer "B.Fab")
		)
		(fp_line
			(start 0.12065 -0.305054)
			(end 0.12065 -0.2794)
			(stroke
				(width 0.1)
				(type default)
			)
			(layer "B.Fab")
		)
		(fp_line
			(start 0.12065 -0.2794)
			(end -0.12065 -0.2794)
			(stroke
				(width 0.1)
				(type default)
			)
			(layer "B.Fab")
		)
		(fp_line
			(start 0.12065 0.2794)
			(end 0.12065 0.3048)
			(stroke
				(width 0.1)
				(type default)
			)
			(layer "B.Fab")
		)
		(fp_line
			(start 0.12065 0.3048)
			(end 0.67945 0.3048)
			(stroke
				(width 0.1)
				(type default)
			)
			(layer "B.Fab")
		)
		(fp_line
			(start 0.67945 -0.305054)
			(end 0.12065 -0.305054)
			(stroke
				(width 0.1)
				(type default)
			)
			(layer "B.Fab")
		)
		(fp_line
			(start 0.67945 0.3048)
			(end 0.67945 -0.305054)
			(stroke
				(width 0.1)
				(type default)
			)
			(layer "B.Fab")
		)
		(pad "1" smd circle
			(at 0.40005 0 180)
			(size 0 0)
			(layers "B.Cu" "B.Mask" "B.Paste")
			(net "SMB_VR_3V3AUX_SCL")
		)
		(pad "2" smd circle
			(at -0.40005 0 180)
			(size 0 0)
			(layers "B.Cu" "B.Mask" "B.Paste")
			(net "SMB_VR_3V3STBY_SCL")
		)
	)
	(footprint ""
		(layer "B.Cu")
		(at 101.385878 -144.63141 180)
		(property "Reference" "PC253"
			(at 0 0 0)
			(layer "B.SilkS")
			(hide yes)
			(effects
				(font
					(size 1.27 1.27)
				)
				(justify mirror)
			)
		)
		(property "Value" ""
			(at 0 0 0)
			(layer "B.Fab")
			(effects
				(font
					(size 1.27 1.27)
				)
				(justify mirror)
			)
		)
		(duplicate_pad_numbers_are_jumpers no)
		(fp_line
			(start 0.7874 0.4064)
			(end 0.7874 -0.4064)
			(stroke
				(width 0.1524)
				(type default)
			)
			(layer "B.SilkS")
		)
		(fp_line
			(start 0.7874 -0.4064)
			(end -0.7874 -0.4064)
			(stroke
				(width 0.1524)
				(type default)
			)
			(layer "B.SilkS")
		)
		(fp_line
			(start -0.7874 0.4064)
			(end 0.7874 0.4064)
			(stroke
				(width 0.1524)
				(type default)
			)
			(layer "B.SilkS")
		)
		(fp_line
			(start -0.7874 -0.4064)
			(end -0.7874 0.4064)
			(stroke
				(width 0.1524)
				(type default)
			)
			(layer "B.SilkS")
		)
		(fp_line
			(start 0.67945 0.3048)
			(end 0.67945 -0.305054)
			(stroke
				(width 0.1)
				(type default)
			)
			(layer "B.Fab")
		)
		(fp_line
			(start 0.67945 -0.305054)
			(end 0.12065 -0.305054)
			(stroke
				(width 0.1)
				(type default)
			)
			(layer "B.Fab")
		)
		(fp_line
			(start 0.12065 0.3048)
			(end 0.67945 0.3048)
			(stroke
				(width 0.1)
				(type default)
			)
			(layer "B.Fab")
		)
		(fp_line
			(start 0.12065 0.2794)
			(end 0.12065 0.3048)
			(stroke
				(width 0.1)
				(type default)
			)
			(layer "B.Fab")
		)
		(fp_line
			(start 0.12065 -0.2794)
			(end -0.12065 -0.2794)
			(stroke
				(width 0.1)
				(type default)
			)
			(layer "B.Fab")
		)
		(fp_line
			(start 0.12065 -0.305054)
			(end 0.12065 -0.2794)
			(stroke
				(width 0.1)
				(type default)
			)
			(layer "B.Fab")
		)
		(fp_line
			(start -0.120396 0.3048)
			(end -0.120396 0.2794)
			(stroke
				(width 0.1)
				(type default)
			)
			(layer "B.Fab")
		)
		(fp_line
			(start -0.120396 0.2794)
			(end 0.12065 0.2794)
			(stroke
				(width 0.1)
				(type default)
			)
			(layer "B.Fab")
		)
		(fp_line
			(start -0.12065 -0.2794)
			(end -0.12065 -0.3048)
			(stroke
				(width 0.1)
				(type default)
			)
			(layer "B.Fab")
		)
		(fp_line
			(start -0.12065 -0.3048)
			(end -0.67945 -0.3048)
			(stroke
				(width 0.1)
				(type default)
			)
			(layer "B.Fab")
		)
		(fp_line
			(start -0.67945 0.3048)
			(end -0.120396 0.3048)
			(stroke
				(width 0.1)
				(type default)
			)
			(layer "B.Fab")
		)
		(fp_line
			(start -0.67945 -0.3048)
			(end -0.67945 0.3048)
			(stroke
				(width 0.1)
				(type default)
			)
			(layer "B.Fab")
		)
		(pad "1" smd circle
			(at 0.40005 0)
			(size 0 0)
			(layers "B.Cu" "B.Mask" "B.Paste")
			(net "PVDDCR_SOC_P1_TEMP1")
		)
		(pad "2" smd circle
			(at -0.40005 0)
			(size 0 0)
			(layers "B.Cu" "B.Mask" "B.Paste")
			(net "GND")
		)
	)
)
